# S9S_MB_2U (Grand Teton) — schematic netlist excerpt (pin names and nets, part order shuffled) for the footprints in the layout excerpt that follows; sources: Cadence DE-HDL packaged netlist, KiCad conversion of 03242023_DA0F0TMBIJ0_F0T_Motherboard_J_brd_V01_OCP.brd

R4158  Q_RES  54.9K 1% EMPTY  pkg 0402LF  page 145 : A = P3V3_AUX ; B = GPU_3V3IO_RSVD1
R4013  Q_RES  100K 1% EMPTY  pkg 0402LF  page 242 : A = P3V3_AUX ; B = P12V_SCM_FAULT_R_N

(kicad_pcb
	(version 20260206)
	(generator "pcbnew")
	(generator_version "10.0")
	(general
		(thickness 1.6)
		(legacy_teardrops no)
	)
	(paper "A4")
	(title_block
		(title "03242023_DA0F0TMBIJ0_F0T_Motherboard_J_brd_V01_OCP.brd")
		(comment 1 "Grand Teton / footprints 976-977 of 6105")
	)
	(layers
		(0 "F.Cu" signal "TOP")
		(4 "In1.Cu" signal "GND")
		(6 "In2.Cu" signal "IN1")
		(8 "In3.Cu" signal "GND1")
		(10 "In4.Cu" signal "IN2")
		(12 "In5.Cu" signal "GND2")
		(14 "In6.Cu" signal "IN3")
		(16 "In7.Cu" signal "GND3")
		(18 "In8.Cu" signal "VCC")
		(20 "In9.Cu" signal "VCC1")
		(22 "In10.Cu" signal "GND4")
		(24 "In11.Cu" signal "IN4")
		(26 "In12.Cu" signal "GND5")
		(28 "In13.Cu" signal "IN5")
		(30 "In14.Cu" signal "GND6")
		(32 "In15.Cu" signal "IN6")
		(34 "In16.Cu" signal "GND7")
		(2 "B.Cu" signal "BOTTOM")
		(9 "F.Adhes" user "F.Adhesive")
		(11 "B.Adhes" user "B.Adhesive")
		(13 "F.Paste" user "Package Geometry/Pastemask Top")
		(15 "B.Paste" user "Package Geometry/Pastemask Bottom")
		(5 "F.SilkS" user "Ref Des/Silkscreen Top")
		(7 "B.SilkS" user "Ref Des/Silkscreen Bottom")
		(1 "F.Mask" user "Board Geometry/Soldermask Top")
		(3 "B.Mask" user "Board Geometry/Soldermask Bottom")
		(17 "Dwgs.User" user "User.Drawings")
		(19 "Cmts.User" user "User.Comments")
		(21 "Eco1.User" user "User.Eco1")
		(23 "Eco2.User" user "User.Eco2")
		(25 "Edge.Cuts" user "Board Geometry/Outline")
		(27 "Margin" user)
		(31 "F.CrtYd" user "Package Geometry/Place Bound Top")
		(29 "B.CrtYd" user "Package Geometry/Place Bound Bottom")
		(35 "F.Fab" user "Ref Des/Assembly Top")
		(33 "B.Fab" user "Ref Des/Assembly Bottom")
	)
	(footprint ""
		(layer "F.Cu")
		(at 193.089022 -25.965912 90)
		(property "Reference" "R4013"
			(at 0 0 90)
			(layer "F.SilkS")
			(hide yes)
			(effects
				(font
					(size 1.27 1.27)
				)
			)
		)
		(property "Value" ""
			(at 0 0 90)
			(layer "F.Fab")
			(effects
				(font
					(size 1.27 1.27)
				)
			)
		)
		(duplicate_pad_numbers_are_jumpers no)
		(fp_line
			(start 0.7874 -0.4064)
			(end 0.7874 0.4064)
			(stroke
				(width 0.1524)
				(type default)
			)
			(layer "F.SilkS")
		)
		(fp_line
			(start -0.7874 -0.4064)
			(end 0.7874 -0.4064)
			(stroke
				(width 0.1524)
				(type default)
			)
			(layer "F.SilkS")
		)
		(fp_line
			(start 0.7874 0.4064)
			(end -0.7874 0.4064)
			(stroke
				(width 0.1524)
				(type default)
			)
			(layer "F.SilkS")
		)
		(fp_line
			(start -0.7874 0.4064)
			(end -0.7874 -0.4064)
			(stroke
				(width 0.1524)
				(type default)
			)
			(layer "F.SilkS")
		)
		(fp_line
			(start -0.12065 -0.305054)
			(end -0.12065 -0.2794)
			(stroke
				(width 0.1)
				(type default)
			)
			(layer "F.Fab")
		)
		(fp_line
			(start -0.67945 -0.305054)
			(end -0.12065 -0.305054)
			(stroke
				(width 0.1)
				(type default)
			)
			(layer "F.Fab")
		)
		(fp_line
			(start 0.67945 -0.3048)
			(end 0.67945 0.3048)
			(stroke
				(width 0.1)
				(type default)
			)
			(layer "F.Fab")
		)
		(fp_line
			(start 0.12065 -0.3048)
			(end 0.67945 -0.3048)
			(stroke
				(width 0.1)
				(type default)
			)
			(layer "F.Fab")
		)
		(fp_line
			(start 0.12065 -0.2794)
			(end 0.12065 -0.3048)
			(stroke
				(width 0.1)
				(type default)
			)
			(layer "F.Fab")
		)
		(fp_line
			(start -0.12065 -0.2794)
			(end 0.12065 -0.2794)
			(stroke
				(width 0.1)
				(type default)
			)
			(layer "F.Fab")
		)
		(fp_line
			(start 0.120396 0.2794)
			(end -0.12065 0.2794)
			(stroke
				(width 0.1)
				(type default)
			)
			(layer "F.Fab")
		)
		(fp_line
			(start -0.12065 0.2794)
			(end -0.12065 0.3048)
			(stroke
				(width 0.1)
				(type default)
			)
			(layer "F.Fab")
		)
		(fp_line
			(start 0.67945 0.3048)
			(end 0.120396 0.3048)
			(stroke
				(width 0.1)
				(type default)
			)
			(layer "F.Fab")
		)
		(fp_line
			(start 0.120396 0.3048)
			(end 0.120396 0.2794)
			(stroke
				(width 0.1)
				(type default)
			)
			(layer "F.Fab")
		)
		(fp_line
			(start -0.12065 0.3048)
			(end -0.67945 0.3048)
			(stroke
				(width 0.1)
				(type default)
			)
			(layer "F.Fab")
		)
		(fp_line
			(start -0.67945 0.3048)
			(end -0.67945 -0.305054)
			(stroke
				(width 0.1)
				(type default)
			)
			(layer "F.Fab")
		)
		(pad "1" smd circle
			(at -0.40005 0 90)
			(size 0 0)
			(layers "F.Cu" "F.Mask" "F.Paste")
			(net "P3V3_AUX")
		)
		(pad "2" smd circle
			(at 0.40005 0 90)
			(size 0 0)
			(layers "F.Cu" "F.Mask" "F.Paste")
			(net "P12V_SCM_FAULT_R_N")
		)
	)
	(footprint ""
		(layer "F.Cu")
		(at 360.383582 -386.41909)
		(property "Reference" "R4158"
			(at 0 0 0)
			(layer "F.SilkS")
			(hide yes)
			(effects
				(font
					(size 1.27 1.27)
				)
			)
		)
		(property "Value" ""
			(at 0 0 0)
			(layer "F.Fab")
			(effects
				(font
					(size 1.27 1.27)
				)
			)
		)
		(duplicate_pad_numbers_are_jumpers no)
		(fp_line
			(start -0.7874 -0.4064)
			(end 0.7874 -0.4064)
			(stroke
				(width 0.1524)
				(type default)
			)
			(layer "F.SilkS")
		)
		(fp_line
			(start -0.7874 0.4064)
			(end -0.7874 -0.4064)
			(stroke
				(width 0.1524)
				(type default)
			)
			(layer "F.SilkS")
		)
		(fp_line
			(start 0.7874 -0.4064)
			(end 0.7874 0.4064)
			(stroke
				(width 0.1524)
				(type default)
			)
			(layer "F.SilkS")
		)
		(fp_line
			(start 0.7874 0.4064)
			(end -0.7874 0.4064)
			(stroke
				(width 0.1524)
				(type default)
			)
			(layer "F.SilkS")
		)
		(fp_line
			(start -0.67945 -0.305054)
			(end -0.12065 -0.305054)
			(stroke
				(width 0.1)
				(type default)
			)
			(layer "F.Fab")
		)
		(fp_line
			(start -0.67945 0.3048)
			(end -0.67945 -0.305054)
			(stroke
				(width 0.1)
				(type default)
			)
			(layer "F.Fab")
		)
		(fp_line
			(start -0.12065 -0.305054)
			(end -0.12065 -0.2794)
			(stroke
				(width 0.1)
				(type default)
			)
			(layer "F.Fab")
		)
		(fp_line
			(start -0.12065 -0.2794)
			(end 0.12065 -0.2794)
			(stroke
				(width 0.1)
				(type default)
			)
			(layer "F.Fab")
		)
		(fp_line
			(start -0.12065 0.2794)
			(end -0.12065 0.3048)
			(stroke
				(width 0.1)
				(type default)
			)
			(layer "F.Fab")
		)
		(fp_line
			(start -0.12065 0.3048)
			(end -0.67945 0.3048)
			(stroke
				(width 0.1)
				(type default)
			)
			(layer "F.Fab")
		)
		(fp_line
			(start 0.120396 0.2794)
			(end -0.12065 0.2794)
			(stroke
				(width 0.1)
				(type default)
			)
			(layer "F.Fab")
		)
		(fp_line
			(start 0.120396 0.3048)
			(end 0.120396 0.2794)
			(stroke
				(width 0.1)
				(type default)
			)
			(layer "F.Fab")
		)
		(fp_line
			(start 0.12065 -0.3048)
			(end 0.67945 -0.3048)
			(stroke
				(width 0.1)
				(type default)
			)
			(layer "F.Fab")
		)
		(fp_line
			(start 0.12065 -0.2794)
			(end 0.12065 -0.3048)
			(stroke
				(width 0.1)
				(type default)
			)
			(layer "F.Fab")
		)
		(fp_line
			(start 0.67945 -0.3048)
			(end 0.67945 0.3048)
			(stroke
				(width 0.1)
				(type default)
			)
			(layer "F.Fab")
		)
		(fp_line
			(start 0.67945 0.3048)
			(end 0.120396 0.3048)
			(stroke
				(width 0.1)
				(type default)
			)
			(layer "F.Fab")
		)
		(pad "1" smd circle
			(at -0.40005 0)
			(size 0 0)
			(layers "F.Cu" "F.Mask" "F.Paste")
			(net "P3V3_AUX")
		)
		(pad "2" smd circle
			(at 0.40005 0)
			(size 0 0)
			(layers "F.Cu" "F.Mask" "F.Paste")
			(net "GPU_3V3IO_RSVD1")
		)
	)
)
